(kicad_pcb
	(version 20260206)
	(generator "pcbnew")
	(generator_version "10.0")
	(general
		(thickness 1.6)
		(legacy_teardrops no)
	)
	(paper "A4")
	(title_block
		(title "01162023_DA0F0TEBIF0_F0T_Expander_BD_F_brd_V02_OCP.brd")
		(comment 1 "Grand Teton / footprints 1212-1213 of 9728")
	)
	(layers
		(0 "F.Cu" signal "TOP")
		(4 "In1.Cu" signal "GND")
		(6 "In2.Cu" signal "VCC")
		(8 "In3.Cu" signal "VCC1")
		(10 "In4.Cu" signal "GND1")
		(12 "In5.Cu" signal "IN1")
		(14 "In6.Cu" signal "GND2")
		(16 "In7.Cu" signal "IN2")
		(18 "In8.Cu" signal "GND3")
		(20 "In9.Cu" signal "IN3")
		(22 "In10.Cu" signal "GND4")
		(24 "In11.Cu" signal "IN4")
		(26 "In12.Cu" signal "GND5")
		(28 "In13.Cu" signal "IN5")
		(30 "In14.Cu" signal "GND6")
		(32 "In15.Cu" signal "IN6")
		(34 "In16.Cu" signal "GND7")
		(2 "B.Cu" signal "BOTTOM")
		(9 "F.Adhes" user "F.Adhesive")
		(11 "B.Adhes" user "B.Adhesive")
		(13 "F.Paste" user "Package Geometry/Pastemask Top")
		(15 "B.Paste" user "Package Geometry/Pastemask Bottom")
		(5 "F.SilkS" user "Ref Des/Silkscreen Top")
		(7 "B.SilkS" user "Ref Des/Silkscreen Bottom")
		(1 "F.Mask" user "Board Geometry/Soldermask Top")
		(3 "B.Mask" user "Board Geometry/Soldermask Bottom")
		(17 "Dwgs.User" user "User.Drawings")
		(19 "Cmts.User" user "User.Comments")
		(21 "Eco1.User" user "User.Eco1")
		(23 "Eco2.User" user "User.Eco2")
		(25 "Edge.Cuts" user "Board Geometry/Outline")
		(27 "Margin" user)
		(31 "F.CrtYd" user "Package Geometry/Place Bound Top")
		(29 "B.CrtYd" user "Package Geometry/Place Bound Bottom")
		(35 "F.Fab" user "Ref Des/Assembly Top")
		(33 "B.Fab" user "Ref Des/Assembly Bottom")
	)
	(footprint ""
		(layer "F.Cu")
		(at 338.796884 -116.611654 180)
		(property "Reference" "PR7031"
			(at 0 0 180)
			(layer "F.SilkS")
			(hide yes)
			(effects
				(font
					(size 1.27 1.27)
				)
			)
		)
		(property "Value" ""
			(at 0 0 180)
			(layer "F.Fab")
			(effects
				(font
					(size 1.27 1.27)
				)
			)
		)
		(duplicate_pad_numbers_are_jumpers no)
		(fp_line
			(start 0.7874 0.4064)
			(end -0.7874 0.4064)
			(stroke
				(width 0.1524)
				(type default)
			)
			(layer "F.SilkS")
		)
		(fp_line
			(start 0.7874 -0.4064)
			(end 0.7874 0.4064)
			(stroke
				(width 0.1524)
				(type default)
			)
			(layer "F.SilkS")
		)
		(fp_line
			(start -0.7874 0.4064)
			(end -0.7874 -0.4064)
			(stroke
				(width 0.1524)
				(type default)
			)
			(layer "F.SilkS")
		)
		(fp_line
			(start -0.7874 -0.4064)
			(end 0.7874 -0.4064)
			(stroke
				(width 0.1524)
				(type default)
			)
			(layer "F.SilkS")
		)
		(fp_line
			(start 0.67945 0.3048)
			(end 0.120396 0.3048)
			(stroke
				(width 0.1)
				(type default)
			)
			(layer "F.Fab")
		)
		(fp_line
			(start 0.67945 -0.3048)
			(end 0.67945 0.3048)
			(stroke
				(width 0.1)
				(type default)
			)
			(layer "F.Fab")
		)
		(fp_line
			(start 0.12065 -0.2794)
			(end 0.12065 -0.3048)
			(stroke
				(width 0.1)
				(type default)
			)
			(layer "F.Fab")
		)
		(fp_line
			(start 0.12065 -0.3048)
			(end 0.67945 -0.3048)
			(stroke
				(width 0.1)
				(type default)
			)
			(layer "F.Fab")
		)
		(fp_line
			(start 0.120396 0.3048)
			(end 0.120396 0.2794)
			(stroke
				(width 0.1)
				(type default)
			)
			(layer "F.Fab")
		)
		(fp_line
			(start 0.120396 0.2794)
			(end -0.12065 0.2794)
			(stroke
				(width 0.1)
				(type default)
			)
			(layer "F.Fab")
		)
		(fp_line
			(start -0.12065 0.3048)
			(end -0.67945 0.3048)
			(stroke
				(width 0.1)
				(type default)
			)
			(layer "F.Fab")
		)
		(fp_line
			(start -0.12065 0.2794)
			(end -0.12065 0.3048)
			(stroke
				(width 0.1)
				(type default)
			)
			(layer "F.Fab")
		)
		(fp_line
			(start -0.12065 -0.2794)
			(end 0.12065 -0.2794)
			(stroke
				(width 0.1)
				(type default)
			)
			(layer "F.Fab")
		)
		(fp_line
			(start -0.12065 -0.305054)
			(end -0.12065 -0.2794)
			(stroke
				(width 0.1)
				(type default)
			)
			(layer "F.Fab")
		)
		(fp_line
			(start -0.67945 0.3048)
			(end -0.67945 -0.305054)
			(stroke
				(width 0.1)
				(type default)
			)
			(layer "F.Fab")
		)
		(fp_line
			(start -0.67945 -0.305054)
			(end -0.12065 -0.305054)
			(stroke
				(width 0.1)
				(type default)
			)
			(layer "F.Fab")
		)
		(pad "1" smd circle
			(at -0.40005 0 180)
			(size 0 0)
			(layers "F.Cu" "F.Mask" "F.Paste")
			(net "P12V_NIC5_CO_OV_FB")
		)
		(pad "2" smd circle
			(at 0.40005 0 180)
			(size 0 0)
			(layers "F.Cu" "F.Mask" "F.Paste")
			(net "P12V_AUX")
		)
	)
	(footprint ""
		(layer "F.Cu")
		(at 297.16476 -26.785062 180)
		(property "Reference" "J40"
			(at 4.09829 -11.087862 90)
			(unlocked yes)
			(layer "F.SilkS")
			(effects
				(font
					(size 0.7874 0.5842)
					(thickness 0.1524)
				)
			)
		)
		(property "Value" ""
			(at 0 0 180)
			(layer "F.Fab")
			(effects
				(font
					(size 1.27 1.27)
				)
			)
		)
		(duplicate_pad_numbers_are_jumpers no)
		(fp_line
			(start 3.150108 12.115038)
			(end 1.529334 12.115038)
			(stroke
				(width 0.1524)
				(type default)
			)
			(layer "F.SilkS")
		)
		(fp_line
			(start 3.074924 12.014962)
			(end 1.632204 12.014962)
			(stroke
				(width 0.1524)
				(type default)
			)
			(layer "F.SilkS")
		)
		(fp_line
			(start 1.632204 -12.014962)
			(end 3.074924 -12.014962)
			(stroke
				(width 0.1524)
				(type default)
			)
			(layer "F.SilkS")
		)
		(fp_line
			(start 1.529334 -12.115038)
			(end 3.150108 -12.115038)
			(stroke
				(width 0.1524)
				(type default)
			)
			(layer "F.SilkS")
		)
		(fp_line
			(start -1.529334 12.115038)
			(end -3.150108 12.115038)
			(stroke
				(width 0.1524)
				(type default)
			)
			(layer "F.SilkS")
		)
		(fp_line
			(start -1.632204 12.014962)
			(end -3.074924 12.014962)
			(stroke
				(width 0.1524)
				(type default)
			)
			(layer "F.SilkS")
		)
		(fp_line
			(start -3.074924 -12.014962)
			(end -1.632204 -12.014962)
			(stroke
				(width 0.1524)
				(type default)
			)
			(layer "F.SilkS")
		)
		(fp_line
			(start -3.150108 -12.115038)
			(end -1.529334 -12.115038)
			(stroke
				(width 0.1524)
				(type default)
			)
			(layer "F.SilkS")
		)
		(fp_poly
			(pts
				(xy 3.550666 -8.697722) (xy 3.973068 -9.965436) (xy 4.818126 -9.120378)
			)
			(stroke
				(width 0)
				(type default)
			)
			(fill yes)
			(layer "F.SilkS")
		)
		(fp_line
			(start 3.074924 12.014962)
			(end -3.074924 12.014962)
			(stroke
				(width 0.1)
				(type default)
			)
			(layer "F.Fab")
		)
		(fp_line
			(start 3.074924 -12.014962)
			(end 3.074924 12.014962)
			(stroke
				(width 0.1)
				(type default)
			)
			(layer "F.Fab")
		)
		(fp_line
			(start -3.074924 12.014962)
			(end -3.074924 -12.014962)
			(stroke
				(width 0.1)
				(type default)
			)
			(layer "F.Fab")
		)
		(fp_line
			(start -3.074924 -12.014962)
			(end 3.074924 -12.014962)
			(stroke
				(width 0.1)
				(type default)
			)
			(layer "F.Fab")
		)
		(fp_poly
			(pts
				(xy 3.348736 -7.994904) (xy 4.543806 -8.592566) (xy 4.543806 -7.397496)
			)
			(stroke
				(width 0)
				(type default)
			)
			(fill yes)
			(layer "F.Fab")
		)
		(pad "" np_thru_hole circle
			(at -1.75006 -9.815068 90)
			(size 1.1176 1.1176)
			(drill 1.1176)
			(layers "*.Cu" "*.Mask")
			(clearance 0.381)
			(thermal_gap 0.381)
		)
		(pad "" np_thru_hole circle
			(at 0 9.815068 90)
			(size 1.1176 1.1176)
			(drill 1.1176)
			(layers "*.Cu" "*.Mask")
			(clearance 0.381)
			(thermal_gap 0.381)
		)
		(pad "A1" smd rect
			(at 2.29997 -7.994904 90)
			(size 0.381 1.27)
			(layers "F.Cu" "F.Mask" "F.Paste")
			(net "GND")
		)
		(pad "A2" smd rect
			(at 2.29997 -7.394956 90)
			(size 0.381 1.27)
			(layers "F.Cu" "F.Mask" "F.Paste")
			(net "GND")
		)
		(pad "A3" smd rect
			(at 2.29997 -6.795008 90)
			(size 0.381 1.27)
			(layers "F.Cu" "F.Mask" "F.Paste")
			(net "GND")
		)
		(pad "A4" smd rect
			(at 2.29997 -6.19506 90)
			(size 0.381 1.27)
			(layers "F.Cu" "F.Mask" "F.Paste")
			(net "GND")
		)
		(pad "A5" smd rect
			(at 2.29997 -5.595112 90)
			(size 0.381 1.27)
			(layers "F.Cu" "F.Mask" "F.Paste")
			(net "GND")
		)
		(pad "A6" smd rect
			(at 2.29997 -4.99491 90)
			(size 0.381 1.27)
			(layers "F.Cu" "F.Mask" "F.Paste")
			(net "GND")
		)
		(pad "A7" smd rect
			(at 2.29997 -4.394962 90)
			(size 0.381 1.27)
			(layers "F.Cu" "F.Mask" "F.Paste")
			(net "SMB_ISO_SSD10_R_SCL")
		)
		(pad "A8" smd rect
			(at 2.29997 -3.795014 90)
			(size 0.381 1.27)
			(layers "F.Cu" "F.Mask" "F.Paste")
			(net "SMB_ISO_SSD10_R_SDA")
		)
		(pad "A9" smd rect
			(at 2.29997 -3.195066 90)
			(size 0.381 1.27)
			(layers "F.Cu" "F.Mask" "F.Paste")
			(net "RST_SMB_SSD10_ISO_R_N")
		)
		(pad "A10" smd rect
			(at 2.29997 -2.595118 90)
			(size 0.381 1.27)
			(layers "F.Cu" "F.Mask" "F.Paste")
			(net "SSD10_LED_ISO_R_N")
		)
		(pad "A11" smd rect
			(at 2.29997 -1.994916 90)
			(size 0.381 1.27)
			(layers "F.Cu" "F.Mask" "F.Paste")
			(net "PU_CLKREQ10")
		)
		(pad "A12" smd rect
			(at 2.29997 -1.394968 90)
			(size 0.381 1.27)
			(layers "F.Cu" "F.Mask" "F.Paste")
			(net "PRSNT_SSD10_N")
		)
		(pad "A13" smd rect
			(at 2.29997 -0.79502 90)
			(size 0.381 1.27)
			(layers "F.Cu" "F.Mask" "F.Paste")
			(net "GND")
		)
		(pad "A14" smd rect
			(at 2.29997 -0.195072 90)
			(size 0.381 1.27)
			(layers "F.Cu" "F.Mask" "F.Paste")
			(net "Net_8489")
		)
		(pad "A15" smd rect
			(at 2.29997 0.404876 90)
			(size 0.381 1.27)
			(layers "F.Cu" "F.Mask" "F.Paste")
			(net "Net_8488")
		)
		(pad "A16" smd rect
			(at 2.29997 1.005078 90)
			(size 0.381 1.27)
			(layers "F.Cu" "F.Mask" "F.Paste")
			(net "GND")
		)
		(pad "A17" smd rect
			(at 2.29997 1.605026 90)
			(size 0.381 1.27)
			(layers "F.Cu" "F.Mask" "F.Paste")
			(net "P5E_PEX2_STN2_RX_DN<36>")
		)
		(pad "A18" smd rect
			(at 2.29997 2.204974 90)
			(size 0.381 1.27)
			(layers "F.Cu" "F.Mask" "F.Paste")
			(net "P5E_PEX2_STN2_RX_DP<36>")
		)
		(pad "A19" smd rect
			(at 2.29997 2.804922 90)
			(size 0.381 1.27)
			(layers "F.Cu" "F.Mask" "F.Paste")
			(net "GND")
		)
		(pad "A20" smd rect
			(at 2.29997 3.405124 90)
			(size 0.381 1.27)
			(layers "F.Cu" "F.Mask" "F.Paste")
			(net "P5E_PEX2_STN2_RX_DN<37>")
		)
		(pad "A21" smd rect
			(at 2.29997 4.005072 90)
			(size 0.381 1.27)
			(layers "F.Cu" "F.Mask" "F.Paste")
			(net "P5E_PEX2_STN2_RX_DP<37>")
		)
		(pad "A22" smd rect
			(at 2.29997 4.60502 90)
			(size 0.381 1.27)
			(layers "F.Cu" "F.Mask" "F.Paste")
			(net "GND")
		)
		(pad "A23" smd rect
			(at 2.29997 5.204968 90)
			(size 0.381 1.27)
			(layers "F.Cu" "F.Mask" "F.Paste")
			(net "P5E_PEX2_STN2_RX_DN<38>")
		)
		(pad "A24" smd rect
			(at 2.29997 5.804916 90)
			(size 0.381 1.27)
			(layers "F.Cu" "F.Mask" "F.Paste")
			(net "P5E_PEX2_STN2_RX_DP<38>")
		)
		(pad "A25" smd rect
			(at 2.29997 6.405118 90)
			(size 0.381 1.27)
			(layers "F.Cu" "F.Mask" "F.Paste")
			(net "GND")
		)
		(pad "A26" smd rect
			(at 2.29997 7.005066 90)
			(size 0.381 1.27)
			(layers "F.Cu" "F.Mask" "F.Paste")
			(net "P5E_PEX2_STN2_RX_DN<39>")
		)
		(pad "A27" smd rect
			(at 2.29997 7.605014 90)
			(size 0.381 1.27)
			(layers "F.Cu" "F.Mask" "F.Paste")
			(net "P5E_PEX2_STN2_RX_DP<39>")
		)
		(pad "A28" smd rect
			(at 2.29997 8.204962 90)
			(size 0.381 1.27)
			(layers "F.Cu" "F.Mask" "F.Paste")
			(net "GND")
		)
		(pad "B1" smd rect
			(at -2.29997 -7.994904 90)
			(size 0.381 1.27)
			(layers "F.Cu" "F.Mask" "F.Paste")
			(net "P12V_SSD10")
		)
		(pad "B2" smd rect
			(at -2.29997 -7.394956 90)
			(size 0.381 1.27)
			(layers "F.Cu" "F.Mask" "F.Paste")
			(net "P12V_SSD10")
		)
		(pad "B3" smd rect
			(at -2.29997 -6.795008 90)
			(size 0.381 1.27)
			(layers "F.Cu" "F.Mask" "F.Paste")
			(net "P12V_SSD10")
		)
		(pad "B4" smd rect
			(at -2.29997 -6.19506 90)
			(size 0.381 1.27)
			(layers "F.Cu" "F.Mask" "F.Paste")
			(net "P12V_SSD10")
		)
		(pad "B5" smd rect
			(at -2.29997 -5.595112 90)
			(size 0.381 1.27)
			(layers "F.Cu" "F.Mask" "F.Paste")
			(net "P12V_SSD10")
		)
		(pad "B6" smd rect
			(at -2.29997 -4.99491 90)
			(size 0.381 1.27)
			(layers "F.Cu" "F.Mask" "F.Paste")
			(net "P12V_SSD10")
		)
		(pad "B7" smd rect
			(at -2.29997 -4.394962 90)
			(size 0.381 1.27)
			(layers "F.Cu" "F.Mask" "F.Paste")
			(net "Net_8490")
		)
		(pad "B8" smd rect
			(at -2.29997 -3.795014 90)
			(size 0.381 1.27)
			(layers "F.Cu" "F.Mask" "F.Paste")
			(net "Net_8487")
		)
		(pad "B9" smd rect
			(at -2.29997 -3.195066 90)
			(size 0.381 1.27)
			(layers "F.Cu" "F.Mask" "F.Paste")
			(net "DUALPORT_N_SSD10")
		)
		(pad "B10" smd rect
			(at -2.29997 -2.595118 90)
			(size 0.381 1.27)
			(layers "F.Cu" "F.Mask" "F.Paste")
			(net "RST_SSD10_PERST_R_N")
		)
		(pad "B11" smd rect
			(at -2.29997 -1.994916 90)
			(size 0.381 1.27)
			(layers "F.Cu" "F.Mask" "F.Paste")
			(net "P3V3_SSD10")
		)
		(pad "B12" smd rect
			(at -2.29997 -1.394968 90)
			(size 0.381 1.27)
			(layers "F.Cu" "F.Mask" "F.Paste")
			(net "SSD10_PWRDIS_R")
		)
		(pad "B13" smd rect
			(at -2.29997 -0.79502 90)
			(size 0.381 1.27)
			(layers "F.Cu" "F.Mask" "F.Paste")
			(net "GND")
		)
		(pad "B14" smd rect
			(at -2.29997 -0.195072 90)
			(size 0.381 1.27)
			(layers "F.Cu" "F.Mask" "F.Paste")
			(net "CLK_100M_DB800ZL_SSD10_R_DN")
		)
		(pad "B15" smd rect
			(at -2.29997 0.404876 90)
			(size 0.381 1.27)
			(layers "F.Cu" "F.Mask" "F.Paste")
			(net "CLK_100M_DB800ZL_SSD10_R_DP")
		)
		(pad "B16" smd rect
			(at -2.29997 1.005078 90)
			(size 0.381 1.27)
			(layers "F.Cu" "F.Mask" "F.Paste")
			(net "GND")
		)
		(pad "B17" smd rect
			(at -2.29997 1.605026 90)
			(size 0.381 1.27)
			(layers "F.Cu" "F.Mask" "F.Paste")
			(net "P5E_PEX2_STN2_TX_C_DN<36>")
		)
		(pad "B18" smd rect
			(at -2.29997 2.204974 90)
			(size 0.381 1.27)
			(layers "F.Cu" "F.Mask" "F.Paste")
			(net "P5E_PEX2_STN2_TX_C_DP<36>")
		)
		(pad "B19" smd rect
			(at -2.29997 2.804922 90)
			(size 0.381 1.27)
			(layers "F.Cu" "F.Mask" "F.Paste")
			(net "GND")
		)
		(pad "B20" smd rect
			(at -2.29997 3.405124 90)
			(size 0.381 1.27)
			(layers "F.Cu" "F.Mask" "F.Paste")
			(net "P5E_PEX2_STN2_TX_C_DN<37>")
		)
		(pad "B21" smd rect
			(at -2.29997 4.005072 90)
			(size 0.381 1.27)
			(layers "F.Cu" "F.Mask" "F.Paste")
			(net "P5E_PEX2_STN2_TX_C_DP<37>")
		)
		(pad "B22" smd rect
			(at -2.29997 4.60502 90)
			(size 0.381 1.27)
			(layers "F.Cu" "F.Mask" "F.Paste")
			(net "GND")
		)
		(pad "B23" smd rect
			(at -2.29997 5.204968 90)
			(size 0.381 1.27)
			(layers "F.Cu" "F.Mask" "F.Paste")
			(net "P5E_PEX2_STN2_TX_C_DN<38>")
		)
		(pad "B24" smd rect
			(at -2.29997 5.804916 90)
			(size 0.381 1.27)
			(layers "F.Cu" "F.Mask" "F.Paste")
			(net "P5E_PEX2_STN2_TX_C_DP<38>")
		)
		(pad "B25" smd rect
			(at -2.29997 6.405118 90)
			(size 0.381 1.27)
			(layers "F.Cu" "F.Mask" "F.Paste")
			(net "GND")
		)
		(pad "B26" smd rect
			(at -2.29997 7.005066 90)
			(size 0.381 1.27)
			(layers "F.Cu" "F.Mask" "F.Paste")
			(net "P5E_PEX2_STN2_TX_C_DN<39>")
		)
		(pad "B27" smd rect
			(at -2.29997 7.605014 90)
			(size 0.381 1.27)
			(layers "F.Cu" "F.Mask" "F.Paste")
			(net "P5E_PEX2_STN2_TX_C_DP<39>")
		)
		(pad "B28" smd rect
			(at -2.29997 8.204962 90)
			(size 0.381 1.27)
			(layers "F.Cu" "F.Mask" "F.Paste")
			(net "GND")
		)
		(pad "G1" thru_hole oval
			(at 0 -11.364976 90)
			(size 1.6256 3.4798)
			(drill oval 1.1176 2.4638)
			(layers "*.Cu" "*.Mask")
			(remove_unused_layers no)
			(net "GND")
			(clearance 0.127)
			(thermal_gap 0.127)
		)
		(pad "G2" thru_hole oval
			(at 0 11.364976 90)
			(size 1.6256 3.4798)
			(drill oval 1.1176 2.4638)
			(layers "*.Cu" "*.Mask")
			(remove_unused_layers no)
			(net "GND")
			(clearance 0.127)
			(thermal_gap 0.127)
		)
		(zone
			(layer "F.Cu")
			(hatch none 0.5)
			(connect_pads
				(clearance 0)
			)
			(min_thickness 0.25)
			(keepout
				(tracks not_allowed)
				(vias allowed)
				(pads allowed)
				(copperpour not_allowed)
				(footprints allowed)
			)
			(placement
				(enabled no)
				(sheetname "")
			)
			(fill
				(thermal_gap 0.5)
				(thermal_bridge_width 0.5)
				(island_removal_mode 0)
			)
			(polygon
				(pts
					(xy 298.544742 -38.850062) (xy 295.794684 -38.850062) (xy 295.794684 -35.900106) (xy 298.544742 -35.900106)
				)
			)
		)
		(zone
			(layer "F.Cu")
			(hatch none 0.5)
			(connect_pads
				(clearance 0)
			)
			(min_thickness 0.25)
			(keepout
				(tracks not_allowed)
				(vias allowed)
				(pads allowed)
				(copperpour not_allowed)
				(footprints allowed)
			)
			(placement
				(enabled no)
				(sheetname "")
			)
			(fill
				(thermal_gap 0.5)
				(thermal_bridge_width 0.5)
				(island_removal_mode 0)
			)
			(polygon
				(pts
					(xy 299.614844 -17.670018) (xy 295.784778 -17.670018) (xy 295.784778 -14.720062) (xy 299.614844 -14.720062)
				)
			)
		)
		(zone
			(layers "F.Cu" "B.Cu" "In1.Cu" "In2.Cu" "In3.Cu" "In4.Cu" "In5.Cu" "In6.Cu"
				"In7.Cu" "In8.Cu" "In9.Cu" "In10.Cu" "In11.Cu" "In12.Cu" "In13.Cu" "In14.Cu"
				"In15.Cu" "In16.Cu"
			)
			(hatch none 0.5)
			(connect_pads
				(clearance 0)
			)
			(min_thickness 0.25)
			(keepout
				(tracks not_allowed)
				(vias allowed)
				(pads allowed)
				(copperpour not_allowed)
				(footprints allowed)
			)
			(placement
				(enabled no)
				(sheetname "")
			)
			(fill
				(thermal_gap 0.5)
				(thermal_bridge_width 0.5)
				(island_removal_mode 0)
			)
			(polygon
				(pts
					(arc
						(start 298.12996 -36.60013)
						(mid 296.19956 -36.60013)
						(end 298.12996 -36.60013)
					)
				)
			)
		)
		(zone
			(layers "F.Cu" "B.Cu" "In1.Cu" "In2.Cu" "In3.Cu" "In4.Cu" "In5.Cu" "In6.Cu"
				"In7.Cu" "In8.Cu" "In9.Cu" "In10.Cu" "In11.Cu" "In12.Cu" "In13.Cu" "In14.Cu"
				"In15.Cu" "In16.Cu"
			)
			(hatch none 0.5)
			(connect_pads
				(clearance 0)
			)
			(min_thickness 0.25)
			(keepout
				(tracks not_allowed)
				(vias allowed)
				(pads allowed)
				(copperpour not_allowed)
				(footprints allowed)
			)
			(placement
				(enabled no)
				(sheetname "")
			)
			(fill
				(thermal_gap 0.5)
				(thermal_bridge_width 0.5)
				(island_removal_mode 0)
			)
			(polygon
				(pts
					(arc
						(start 299.88002 -16.969994)
						(mid 297.94962 -16.969994)
						(end 299.88002 -16.969994)
					)
				)
			)
		)
	)
)
